(kicad_pcb
	(version 20260206)
	(generator "pcbnew")
	(generator_version "10.0")
	(general
		(thickness 1.6)
		(legacy_teardrops no)
	)
	(paper "A4")
	(title_block
		(title "fcb — Lightning_FCB_BRD.brd")
		(comment 1 "Lightning (Wiwynn / Facebook NVMe JBOF) / footprints 376-382 of 495")
	)
	(layers
		(0 "F.Cu" signal "TOP")
		(4 "In1.Cu" signal "L2GND")
		(6 "In2.Cu" signal "L3VCC")
		(2 "B.Cu" signal "BOTTOM")
		(9 "F.Adhes" user "F.Adhesive")
		(11 "B.Adhes" user "B.Adhesive")
		(13 "F.Paste" user "Package Geometry/Pastemask Top")
		(15 "B.Paste" user "Package Geometry/Pastemask Bottom")
		(5 "F.SilkS" user "Ref Des/Silkscreen Top")
		(7 "B.SilkS" user "Ref Des/Silkscreen Bottom")
		(1 "F.Mask" user "Board Geometry/Soldermask Top")
		(3 "B.Mask" user "Board Geometry/Soldermask Bottom")
		(17 "Dwgs.User" user "User.Drawings")
		(19 "Cmts.User" user "User.Comments")
		(21 "Eco1.User" user "User.Eco1")
		(23 "Eco2.User" user "User.Eco2")
		(25 "Edge.Cuts" user "Board Geometry/Outline")
		(27 "Margin" user)
		(31 "F.CrtYd" user "Package Geometry/Place Bound Top")
		(29 "B.CrtYd" user "Package Geometry/Place Bound Bottom")
		(35 "F.Fab" user "Ref Des/Assembly Top")
		(33 "B.Fab" user "Ref Des/Assembly Bottom")
	)
	(footprint ""
		(layer "F.Cu")
		(at 29.1084 -170.3324 90)
		(property "Reference" "R176"
			(at 0 0 90)
			(layer "F.SilkS")
			(hide yes)
			(effects
				(font
					(size 1.27 1.27)
				)
			)
		)
		(property "Value" "0R2J-2-GP"
			(at 0.064008 -3.993896 90)
			(unlocked yes)
			(layer "F.Fab")
			(hide yes)
			(effects
				(font
					(size 1.016 1.016)
					(thickness 0.1524)
				)
			)
		)
		(property "Device Type" "R402H16"
			(at 0.064008 -5.517896 90)
			(unlocked yes)
			(layer "F.Fab")
			(hide yes)
			(effects
				(font
					(size 1.016 1.016)
					(thickness 0.1524)
				)
			)
		)
		(duplicate_pad_numbers_are_jumpers no)
		(fp_line
			(start 0.508 -0.9398)
			(end -0.508 -0.9398)
			(stroke
				(width 0.1524)
				(type default)
			)
			(layer "F.SilkS")
		)
		(fp_line
			(start -0.508 -0.9398)
			(end -0.508 0.9398)
			(stroke
				(width 0.1524)
				(type default)
			)
			(layer "F.SilkS")
		)
		(fp_rect
			(start -0.508 0.9398)
			(end 0.508 -0.9398)
			(stroke
				(width 0)
				(type default)
			)
			(fill no)
			(layer "F.CrtYd")
		)
		(fp_rect
			(start -0.508 0.9398)
			(end 0.508 -0.9398)
			(stroke
				(width 0)
				(type default)
			)
			(fill no)
			(layer "F.Fab")
		)
		(pad "1" smd custom
			(at 0 -0.4445 90)
			(size 0.1397 0.1397)
			(layers "F.Cu" "F.Mask" "F.Paste")
			(net "PWM_OUT")
			(options
				(clearance outline)
				(anchor circle)
			)
			(primitives
				(gr_poly
					(pts
						(arc
							(start -0.1778 -0.2794)
							(mid -0.249642 -0.249642)
							(end -0.2794 -0.1778)
						)
						(arc
							(start -0.2794 0.1778)
							(mid -0.249642 0.249642)
							(end -0.1778 0.2794)
						)
						(arc
							(start 0.1778 0.2794)
							(mid 0.249642 0.249642)
							(end 0.2794 0.1778)
						)
						(arc
							(start 0.2794 -0.1778)
							(mid 0.249642 -0.249642)
							(end 0.1778 -0.2794)
						)
					)
					(width 0)
					(fill yes)
				)
			)
		)
		(pad "2" smd custom
			(at 0 0.4445 90)
			(size 0.1397 0.1397)
			(layers "F.Cu" "F.Mask" "F.Paste")
			(net "PWM_BUFFER_IN_FAN1_FAN2")
			(options
				(clearance outline)
				(anchor circle)
			)
			(primitives
				(gr_poly
					(pts
						(arc
							(start -0.1778 -0.2794)
							(mid -0.249642 -0.249642)
							(end -0.2794 -0.1778)
						)
						(arc
							(start -0.2794 0.1778)
							(mid -0.249642 0.249642)
							(end -0.1778 0.2794)
						)
						(arc
							(start 0.1778 0.2794)
							(mid 0.249642 0.249642)
							(end 0.2794 0.1778)
						)
						(arc
							(start 0.2794 -0.1778)
							(mid 0.249642 -0.249642)
							(end 0.1778 -0.2794)
						)
					)
					(width 0)
					(fill yes)
				)
			)
		)
	)
	(footprint ""
		(layer "F.Cu")
		(at 21.7424 -21.8948)
		(property "Reference" "F1"
			(at 0 0 0)
			(layer "F.SilkS")
			(hide yes)
			(effects
				(font
					(size 1.27 1.27)
				)
			)
		)
		(property "Value" "FUSE-3A15V-GP"
			(at 0.2286 -10.5918 0)
			(unlocked yes)
			(layer "F.Fab")
			(hide yes)
			(effects
				(font
					(size 1.016 1.016)
					(thickness 0.1524)
				)
			)
		)
		(property "Device Type" "FUSE-7452-UH50"
			(at 0.2286 -12.4968 0)
			(unlocked yes)
			(layer "F.Fab")
			(hide yes)
			(effects
				(font
					(size 1.016 1.016)
					(thickness 0.1524)
				)
			)
		)
		(duplicate_pad_numbers_are_jumpers no)
		(fp_line
			(start -4.9276 -2.921)
			(end 4.9276 -2.921)
			(stroke
				(width 0.1524)
				(type default)
			)
			(layer "F.SilkS")
		)
		(fp_line
			(start -4.9276 2.921)
			(end -4.9276 -2.921)
			(stroke
				(width 0.1524)
				(type default)
			)
			(layer "F.SilkS")
		)
		(fp_line
			(start 4.9276 -2.921)
			(end 4.9276 2.921)
			(stroke
				(width 0.1524)
				(type default)
			)
			(layer "F.SilkS")
		)
		(fp_line
			(start 4.9276 2.921)
			(end -4.9276 2.921)
			(stroke
				(width 0.1524)
				(type default)
			)
			(layer "F.SilkS")
		)
		(fp_poly
			(pts
				(xy -5.08 3.0988) (xy 5.08 3.0988) (xy 5.08 -3.0988) (xy -5.08 -3.0988)
			)
			(stroke
				(width 0)
				(type default)
			)
			(fill no)
			(layer "F.CrtYd")
		)
		(fp_poly
			(pts
				(xy -5.08 -3.0988) (xy 5.08 -3.0988) (xy 5.08 3.0988) (xy -5.08 3.0988)
			)
			(stroke
				(width 0)
				(type default)
			)
			(fill no)
			(layer "F.Fab")
		)
		(pad "1" smd rect
			(at -3.4036 0)
			(size 2.2098 5.2832)
			(layers "F.Cu" "F.Mask" "F.Paste")
			(net "P12V_FAN6")
		)
		(pad "2" smd rect
			(at 3.4036 0)
			(size 2.2098 5.2832)
			(layers "F.Cu" "F.Mask" "F.Paste")
			(net "P12V")
		)
	)
	(footprint ""
		(layer "F.Cu")
		(at 26.67 -153.2128 180)
		(property "Reference" "TP1"
			(at 0 0 180)
			(layer "F.SilkS")
			(hide yes)
			(effects
				(font
					(size 1.27 1.27)
				)
			)
		)
		(property "Value" "TPAD32-GP"
			(at 0 -3.166364 180)
			(unlocked yes)
			(layer "F.Fab")
			(hide yes)
			(effects
				(font
					(size 1.016 1.016)
					(thickness 0.1524)
				)
			)
		)
		(property "Device Type" "TPAD32"
			(at 0 -4.690618 180)
			(unlocked yes)
			(layer "F.Fab")
			(hide yes)
			(effects
				(font
					(size 1.016 1.016)
					(thickness 0.1524)
				)
			)
		)
		(duplicate_pad_numbers_are_jumpers no)
		(fp_poly
			(pts
				(arc
					(start -0.7112 0)
					(mid 0.7112 0)
					(end -0.7112 0)
				)
			)
			(stroke
				(width 0)
				(type default)
			)
			(fill no)
			(layer "F.CrtYd")
		)
		(fp_poly
			(pts
				(arc
					(start -0.7112 0)
					(mid 0.7112 0)
					(end -0.7112 0)
				)
			)
			(stroke
				(width 0)
				(type default)
			)
			(fill no)
			(layer "F.Fab")
		)
		(pad "1" smd circle
			(at 0 0 180)
			(size 0.8128 0.8128)
			(layers "F.Cu" "F.Mask" "F.Paste")
			(net "NCT7904_VREF")
		)
	)
	(footprint ""
		(layer "F.Cu")
		(at 21.0058 -247.9802 90)
		(property "Reference" "U4"
			(at 0 0 90)
			(layer "F.SilkS")
			(hide yes)
			(effects
				(font
					(size 1.27 1.27)
				)
			)
		)
		(property "Value" "SY8201ABC-GP"
			(at -0.0254 -11.9634 90)
			(unlocked yes)
			(layer "F.Fab")
			(hide yes)
			(effects
				(font
					(size 1.016 1.016)
					(thickness 0.1524)
				)
			)
		)
		(property "Device Type" "SOT-6H56"
			(at -0.0254 -13.5636 90)
			(unlocked yes)
			(layer "F.Fab")
			(hide yes)
			(effects
				(font
					(size 1.016 1.016)
					(thickness 0.1524)
				)
			)
		)
		(duplicate_pad_numbers_are_jumpers no)
		(fp_line
			(start 1.7145 -0.5842)
			(end -1.9685 -0.5842)
			(stroke
				(width 0.1524)
				(type default)
			)
			(layer "F.SilkS")
		)
		(fp_line
			(start -1.9685 -0.5842)
			(end -1.9685 0.5842)
			(stroke
				(width 0.1524)
				(type default)
			)
			(layer "F.SilkS")
		)
		(fp_line
			(start -1.9685 -0.4064)
			(end -1.5621 0)
			(stroke
				(width 0.1524)
				(type default)
			)
			(layer "F.SilkS")
		)
		(fp_line
			(start -1.5621 0)
			(end -1.9685 0.4064)
			(stroke
				(width 0.1524)
				(type default)
			)
			(layer "F.SilkS")
		)
		(fp_line
			(start 1.7145 0.5842)
			(end 1.7145 -0.5842)
			(stroke
				(width 0.1524)
				(type default)
			)
			(layer "F.SilkS")
		)
		(fp_line
			(start -1.9685 0.5842)
			(end 1.7145 0.5842)
			(stroke
				(width 0.1524)
				(type default)
			)
			(layer "F.SilkS")
		)
		(fp_line
			(start -1.9685 0.5842)
			(end -1.9685 2.3622)
			(stroke
				(width 0.508)
				(type default)
			)
			(layer "F.SilkS")
		)
		(fp_poly
			(pts
				(xy -1.27 -0.635) (xy 1.27 -0.635) (xy 1.27 0.635) (xy -1.27 0.635)
			)
			(stroke
				(width 0)
				(type default)
			)
			(fill yes)
			(layer "F.SilkS")
		)
		(fp_rect
			(start -1.9685 2.3622)
			(end 1.9685 -2.3622)
			(stroke
				(width 0)
				(type default)
			)
			(fill no)
			(layer "F.CrtYd")
		)
		(fp_poly
			(pts
				(xy -1.9685 -2.3622) (xy 1.9685 -2.3622) (xy 1.9685 2.3622) (xy -1.9685 2.3622)
			)
			(stroke
				(width 0)
				(type default)
			)
			(fill no)
			(layer "F.Fab")
		)
		(pad "1" smd rect
			(at -0.9525 1.3462 90)
			(size 0.5842 1.016)
			(layers "F.Cu" "F.Mask" "F.Paste")
			(net "P3V3_BS_NET")
		)
		(pad "2" smd rect
			(at 0 1.3462 90)
			(size 0.5842 1.016)
			(layers "F.Cu" "F.Mask" "F.Paste")
			(net "GND")
		)
		(pad "3" smd rect
			(at 0.9525 1.3462 90)
			(size 0.5842 1.016)
			(layers "F.Cu" "F.Mask" "F.Paste")
			(net "P3V3_FB")
		)
		(pad "4" smd rect
			(at 0.9525 -1.3462 90)
			(size 0.5842 1.016)
			(layers "F.Cu" "F.Mask" "F.Paste")
			(net "P3V3_EN")
		)
		(pad "5" smd rect
			(at 0 -1.3462 90)
			(size 0.5842 1.016)
			(layers "F.Cu" "F.Mask" "F.Paste")
			(net "P3V3_IN")
		)
		(pad "6" smd rect
			(at -0.9525 -1.3462 90)
			(size 0.5842 1.016)
			(layers "F.Cu" "F.Mask" "F.Paste")
			(net "P3V3_LX")
		)
	)
	(footprint ""
		(layer "F.Cu")
		(at 23.622 -364.4646 -90)
		(property "Reference" "PC3"
			(at 0 0 270)
			(layer "F.SilkS")
			(hide yes)
			(effects
				(font
					(size 1.27 1.27)
				)
			)
		)
		(property "Value" "SCD01U25V2KX-3GP"
			(at 1.1811 -2.7051 270)
			(unlocked yes)
			(layer "F.Fab")
			(hide yes)
			(effects
				(font
					(size 1.016 1.016)
					(thickness 0.1524)
				)
			)
		)
		(property "Device Type" "C402H22"
			(at 1.1811 -4.2291 270)
			(unlocked yes)
			(layer "F.Fab")
			(hide yes)
			(effects
				(font
					(size 1.016 1.016)
					(thickness 0.1524)
				)
			)
		)
		(duplicate_pad_numbers_are_jumpers no)
		(fp_rect
			(start -0.4318 0.9525)
			(end 0.4318 -0.9525)
			(stroke
				(width 0)
				(type default)
			)
			(fill no)
			(layer "F.CrtYd")
		)
		(fp_rect
			(start -0.4318 0.9525)
			(end 0.4318 -0.9525)
			(stroke
				(width 0)
				(type default)
			)
			(fill no)
			(layer "F.Fab")
		)
		(pad "1" smd custom
			(at 0 -0.4445 270)
			(size 0.1524 0.1524)
			(layers "F.Cu" "F.Mask" "F.Paste")
			(net "ADM1276_SS")
			(options
				(clearance outline)
				(anchor circle)
			)
			(primitives
				(gr_poly
					(pts
						(arc
							(start 0.3048 -0.2032)
							(mid 0.275042 -0.275042)
							(end 0.2032 -0.3048)
						)
						(arc
							(start -0.2032 -0.3048)
							(mid -0.275042 -0.275042)
							(end -0.3048 -0.2032)
						)
						(arc
							(start -0.3048 0.2032)
							(mid -0.275042 0.275042)
							(end -0.2032 0.3048)
						)
						(arc
							(start 0.2032 0.3048)
							(mid 0.275042 0.275042)
							(end 0.3048 0.2032)
						)
					)
					(width 0)
					(fill yes)
				)
			)
		)
		(pad "2" smd custom
			(at 0 0.4445 270)
			(size 0.1524 0.1524)
			(layers "F.Cu" "F.Mask" "F.Paste")
			(net "GND")
			(options
				(clearance outline)
				(anchor circle)
			)
			(primitives
				(gr_poly
					(pts
						(arc
							(start 0.3048 -0.2032)
							(mid 0.275042 -0.275042)
							(end 0.2032 -0.3048)
						)
						(arc
							(start -0.2032 -0.3048)
							(mid -0.275042 -0.275042)
							(end -0.3048 -0.2032)
						)
						(arc
							(start -0.3048 0.2032)
							(mid -0.275042 0.275042)
							(end -0.2032 0.3048)
						)
						(arc
							(start 0.2032 0.3048)
							(mid 0.275042 0.275042)
							(end 0.3048 0.2032)
						)
					)
					(width 0)
					(fill yes)
				)
			)
		)
	)
	(footprint ""
		(layer "F.Cu")
		(at 16.51 -148.336 -90)
		(property "Reference" "D4"
			(at 0 0 270)
			(layer "F.SilkS")
			(hide yes)
			(effects
				(font
					(size 1.27 1.27)
				)
			)
		)
		(property "Value" "BAS16H-GP"
			(at 0 -5.5372 270)
			(unlocked yes)
			(layer "F.Fab")
			(hide yes)
			(effects
				(font
					(size 1.016 1.016)
					(thickness 0.1524)
				)
			)
		)
		(property "Device Type" "SOD123AKH48"
			(at 0 -7.0612 270)
			(unlocked yes)
			(layer "F.Fab")
			(hide yes)
			(effects
				(font
					(size 1.016 1.016)
					(thickness 0.1524)
				)
			)
		)
		(duplicate_pad_numbers_are_jumpers no)
		(fp_line
			(start 0.889 2.921)
			(end -0.889 2.921)
			(stroke
				(width 0.508)
				(type default)
			)
			(layer "F.SilkS")
		)
		(fp_line
			(start -1.016 2.667)
			(end 1.016 2.667)
			(stroke
				(width 0.1524)
				(type default)
			)
			(layer "F.SilkS")
		)
		(fp_line
			(start 1.016 2.667)
			(end 1.016 -2.667)
			(stroke
				(width 0.1524)
				(type default)
			)
			(layer "F.SilkS")
		)
		(fp_line
			(start -1.016 -2.667)
			(end -1.016 2.667)
			(stroke
				(width 0.1524)
				(type default)
			)
			(layer "F.SilkS")
		)
		(fp_line
			(start 1.016 -2.667)
			(end -1.016 -2.667)
			(stroke
				(width 0.1524)
				(type default)
			)
			(layer "F.SilkS")
		)
		(fp_rect
			(start -1.143 3.175)
			(end 1.143 -2.794)
			(stroke
				(width 0)
				(type default)
			)
			(fill no)
			(layer "F.CrtYd")
		)
		(fp_poly
			(pts
				(xy -1.143 -2.794) (xy 1.143 -2.794) (xy 1.143 3.175) (xy -1.143 3.175)
			)
			(stroke
				(width 0)
				(type default)
			)
			(fill no)
			(layer "F.Fab")
		)
		(pad "A" smd rect
			(at 0 -1.6891 270)
			(size 0.889 1.397)
			(layers "F.Cu" "F.Mask" "F.Paste")
			(net "FAN_TACH9")
		)
		(pad "K" smd rect
			(at 0 1.6891 270)
			(size 0.889 1.397)
			(layers "F.Cu" "F.Mask" "F.Paste")
			(net "P12V")
		)
	)
	(footprint ""
		(layer "F.Cu")
		(at 9.906 -147.2184 180)
		(property "Reference" "R66"
			(at 0 0 180)
			(layer "F.SilkS")
			(hide yes)
			(effects
				(font
					(size 1.27 1.27)
				)
			)
		)
		(property "Value" "4K7R2F-GP"
			(at 0.064008 -3.993896 180)
			(unlocked yes)
			(layer "F.Fab")
			(hide yes)
			(effects
				(font
					(size 1.016 1.016)
					(thickness 0.1524)
				)
			)
		)
		(property "Device Type" "R402H16"
			(at 0.064008 -5.517896 180)
			(unlocked yes)
			(layer "F.Fab")
			(hide yes)
			(effects
				(font
					(size 1.016 1.016)
					(thickness 0.1524)
				)
			)
		)
		(duplicate_pad_numbers_are_jumpers no)
		(fp_line
			(start 0.508 -0.9398)
			(end -0.508 -0.9398)
			(stroke
				(width 0.1524)
				(type default)
			)
			(layer "F.SilkS")
		)
		(fp_line
			(start -0.508 -0.9398)
			(end -0.508 0.9398)
			(stroke
				(width 0.1524)
				(type default)
			)
			(layer "F.SilkS")
		)
		(fp_rect
			(start -0.508 0.9398)
			(end 0.508 -0.9398)
			(stroke
				(width 0)
				(type default)
			)
			(fill no)
			(layer "F.CrtYd")
		)
		(fp_rect
			(start -0.508 0.9398)
			(end 0.508 -0.9398)
			(stroke
				(width 0)
				(type default)
			)
			(fill no)
			(layer "F.Fab")
		)
		(pad "1" smd custom
			(at 0 -0.4445 180)
			(size 0.1397 0.1397)
			(layers "F.Cu" "F.Mask" "F.Paste")
			(net "P12V")
			(options
				(clearance outline)
				(anchor circle)
			)
			(primitives
				(gr_poly
					(pts
						(arc
							(start -0.1778 -0.2794)
							(mid -0.249642 -0.249642)
							(end -0.2794 -0.1778)
						)
						(arc
							(start -0.2794 0.1778)
							(mid -0.249642 0.249642)
							(end -0.1778 0.2794)
						)
						(arc
							(start 0.1778 0.2794)
							(mid 0.249642 0.249642)
							(end 0.2794 0.1778)
						)
						(arc
							(start 0.2794 -0.1778)
							(mid 0.249642 -0.249642)
							(end 0.1778 -0.2794)
						)
					)
					(width 0)
					(fill yes)
				)
			)
		)
		(pad "2" smd custom
			(at 0 0.4445 180)
			(size 0.1397 0.1397)
			(layers "F.Cu" "F.Mask" "F.Paste")
			(net "FAN_TACH10")
			(options
				(clearance outline)
				(anchor circle)
			)
			(primitives
				(gr_poly
					(pts
						(arc
							(start -0.1778 -0.2794)
							(mid -0.249642 -0.249642)
							(end -0.2794 -0.1778)
						)
						(arc
							(start -0.2794 0.1778)
							(mid -0.249642 0.249642)
							(end -0.1778 0.2794)
						)
						(arc
							(start 0.1778 0.2794)
							(mid 0.249642 0.249642)
							(end 0.2794 0.1778)
						)
						(arc
							(start 0.2794 -0.1778)
							(mid 0.249642 -0.249642)
							(end 0.1778 -0.2794)
						)
					)
					(width 0)
					(fill yes)
				)
			)
		)
	)
)
